# S9S_MB_2U (Grand Teton) — schematic netlist excerpt (pin names and nets, part order shuffled) for the footprints in the layout excerpt that follows; sources: Cadence DE-HDL packaged netlist, KiCad conversion of 03242023_DA0F0TMBIJ0_F0T_Motherboard_J_brd_V01_OCP.brd

R3925  Q_RES  1K 1% CHIP  pkg 0402LF  page 301 : A = IRQ_SML1_PMBUS_ALERT ; B = P3V3_AUX
R3519  Q_RES  4.7K 5% CHIP  pkg 0402LF  page 238 : A = P3V3_OCP_V3_2 ; B = SMB_OCP_V3_2_3V3AUX_BUF_SCL

(kicad_pcb
	(version 20260206)
	(generator "pcbnew")
	(generator_version "10.0")
	(general
		(thickness 1.6)
		(legacy_teardrops no)
	)
	(paper "A4")
	(title_block
		(title "03242023_DA0F0TMBIJ0_F0T_Motherboard_J_brd_V01_OCP.brd")
		(comment 1 "Grand Teton / footprints 1936-1937 of 6105")
	)
	(layers
		(0 "F.Cu" signal "TOP")
		(4 "In1.Cu" signal "GND")
		(6 "In2.Cu" signal "IN1")
		(8 "In3.Cu" signal "GND1")
		(10 "In4.Cu" signal "IN2")
		(12 "In5.Cu" signal "GND2")
		(14 "In6.Cu" signal "IN3")
		(16 "In7.Cu" signal "GND3")
		(18 "In8.Cu" signal "VCC")
		(20 "In9.Cu" signal "VCC1")
		(22 "In10.Cu" signal "GND4")
		(24 "In11.Cu" signal "IN4")
		(26 "In12.Cu" signal "GND5")
		(28 "In13.Cu" signal "IN5")
		(30 "In14.Cu" signal "GND6")
		(32 "In15.Cu" signal "IN6")
		(34 "In16.Cu" signal "GND7")
		(2 "B.Cu" signal "BOTTOM")
		(9 "F.Adhes" user "F.Adhesive")
		(11 "B.Adhes" user "B.Adhesive")
		(13 "F.Paste" user "Package Geometry/Pastemask Top")
		(15 "B.Paste" user "Package Geometry/Pastemask Bottom")
		(5 "F.SilkS" user "Ref Des/Silkscreen Top")
		(7 "B.SilkS" user "Ref Des/Silkscreen Bottom")
		(1 "F.Mask" user "Board Geometry/Soldermask Top")
		(3 "B.Mask" user "Board Geometry/Soldermask Bottom")
		(17 "Dwgs.User" user "User.Drawings")
		(19 "Cmts.User" user "User.Comments")
		(21 "Eco1.User" user "User.Eco1")
		(23 "Eco2.User" user "User.Eco2")
		(25 "Edge.Cuts" user "Board Geometry/Outline")
		(27 "Margin" user)
		(31 "F.CrtYd" user "Package Geometry/Place Bound Top")
		(29 "B.CrtYd" user "Package Geometry/Place Bound Bottom")
		(35 "F.Fab" user "Ref Des/Assembly Top")
		(33 "B.Fab" user "Ref Des/Assembly Bottom")
	)
	(footprint ""
		(layer "F.Cu")
		(at 182.781448 -407.462482 90)
		(property "Reference" "R3925"
			(at 0 0 90)
			(layer "F.SilkS")
			(hide yes)
			(effects
				(font
					(size 1.27 1.27)
				)
			)
		)
		(property "Value" ""
			(at 0 0 90)
			(layer "F.Fab")
			(effects
				(font
					(size 1.27 1.27)
				)
			)
		)
		(duplicate_pad_numbers_are_jumpers no)
		(fp_line
			(start 0.7874 -0.4064)
			(end 0.7874 0.4064)
			(stroke
				(width 0.1524)
				(type default)
			)
			(layer "F.SilkS")
		)
		(fp_line
			(start -0.7874 -0.4064)
			(end 0.7874 -0.4064)
			(stroke
				(width 0.1524)
				(type default)
			)
			(layer "F.SilkS")
		)
		(fp_line
			(start 0.7874 0.4064)
			(end -0.7874 0.4064)
			(stroke
				(width 0.1524)
				(type default)
			)
			(layer "F.SilkS")
		)
		(fp_line
			(start -0.7874 0.4064)
			(end -0.7874 -0.4064)
			(stroke
				(width 0.1524)
				(type default)
			)
			(layer "F.SilkS")
		)
		(fp_line
			(start -0.12065 -0.305054)
			(end -0.12065 -0.2794)
			(stroke
				(width 0.1)
				(type default)
			)
			(layer "F.Fab")
		)
		(fp_line
			(start -0.67945 -0.305054)
			(end -0.12065 -0.305054)
			(stroke
				(width 0.1)
				(type default)
			)
			(layer "F.Fab")
		)
		(fp_line
			(start 0.67945 -0.3048)
			(end 0.67945 0.3048)
			(stroke
				(width 0.1)
				(type default)
			)
			(layer "F.Fab")
		)
		(fp_line
			(start 0.12065 -0.3048)
			(end 0.67945 -0.3048)
			(stroke
				(width 0.1)
				(type default)
			)
			(layer "F.Fab")
		)
		(fp_line
			(start 0.12065 -0.2794)
			(end 0.12065 -0.3048)
			(stroke
				(width 0.1)
				(type default)
			)
			(layer "F.Fab")
		)
		(fp_line
			(start -0.12065 -0.2794)
			(end 0.12065 -0.2794)
			(stroke
				(width 0.1)
				(type default)
			)
			(layer "F.Fab")
		)
		(fp_line
			(start 0.120396 0.2794)
			(end -0.12065 0.2794)
			(stroke
				(width 0.1)
				(type default)
			)
			(layer "F.Fab")
		)
		(fp_line
			(start -0.12065 0.2794)
			(end -0.12065 0.3048)
			(stroke
				(width 0.1)
				(type default)
			)
			(layer "F.Fab")
		)
		(fp_line
			(start 0.67945 0.3048)
			(end 0.120396 0.3048)
			(stroke
				(width 0.1)
				(type default)
			)
			(layer "F.Fab")
		)
		(fp_line
			(start 0.120396 0.3048)
			(end 0.120396 0.2794)
			(stroke
				(width 0.1)
				(type default)
			)
			(layer "F.Fab")
		)
		(fp_line
			(start -0.12065 0.3048)
			(end -0.67945 0.3048)
			(stroke
				(width 0.1)
				(type default)
			)
			(layer "F.Fab")
		)
		(fp_line
			(start -0.67945 0.3048)
			(end -0.67945 -0.305054)
			(stroke
				(width 0.1)
				(type default)
			)
			(layer "F.Fab")
		)
		(pad "1" smd circle
			(at -0.40005 0 90)
			(size 0 0)
			(layers "F.Cu" "F.Mask" "F.Paste")
			(net "IRQ_SML1_PMBUS_ALERT")
		)
		(pad "2" smd circle
			(at 0.40005 0 90)
			(size 0 0)
			(layers "F.Cu" "F.Mask" "F.Paste")
			(net "P3V3_AUX")
		)
	)
	(footprint ""
		(layer "F.Cu")
		(at 98.33864 -31.577788)
		(property "Reference" "R3519"
			(at 0 0 0)
			(layer "F.SilkS")
			(hide yes)
			(effects
				(font
					(size 1.27 1.27)
				)
			)
		)
		(property "Value" ""
			(at 0 0 0)
			(layer "F.Fab")
			(effects
				(font
					(size 1.27 1.27)
				)
			)
		)
		(duplicate_pad_numbers_are_jumpers no)
		(fp_line
			(start -0.7874 -0.4064)
			(end 0.7874 -0.4064)
			(stroke
				(width 0.1524)
				(type default)
			)
			(layer "F.SilkS")
		)
		(fp_line
			(start -0.7874 0.4064)
			(end -0.7874 -0.4064)
			(stroke
				(width 0.1524)
				(type default)
			)
			(layer "F.SilkS")
		)
		(fp_line
			(start 0.7874 -0.4064)
			(end 0.7874 0.4064)
			(stroke
				(width 0.1524)
				(type default)
			)
			(layer "F.SilkS")
		)
		(fp_line
			(start 0.7874 0.4064)
			(end -0.7874 0.4064)
			(stroke
				(width 0.1524)
				(type default)
			)
			(layer "F.SilkS")
		)
		(fp_line
			(start -0.67945 -0.305054)
			(end -0.12065 -0.305054)
			(stroke
				(width 0.1)
				(type default)
			)
			(layer "F.Fab")
		)
		(fp_line
			(start -0.67945 0.3048)
			(end -0.67945 -0.305054)
			(stroke
				(width 0.1)
				(type default)
			)
			(layer "F.Fab")
		)
		(fp_line
			(start -0.12065 -0.305054)
			(end -0.12065 -0.2794)
			(stroke
				(width 0.1)
				(type default)
			)
			(layer "F.Fab")
		)
		(fp_line
			(start -0.12065 -0.2794)
			(end 0.12065 -0.2794)
			(stroke
				(width 0.1)
				(type default)
			)
			(layer "F.Fab")
		)
		(fp_line
			(start -0.12065 0.2794)
			(end -0.12065 0.3048)
			(stroke
				(width 0.1)
				(type default)
			)
			(layer "F.Fab")
		)
		(fp_line
			(start -0.12065 0.3048)
			(end -0.67945 0.3048)
			(stroke
				(width 0.1)
				(type default)
			)
			(layer "F.Fab")
		)
		(fp_line
			(start 0.120396 0.2794)
			(end -0.12065 0.2794)
			(stroke
				(width 0.1)
				(type default)
			)
			(layer "F.Fab")
		)
		(fp_line
			(start 0.120396 0.3048)
			(end 0.120396 0.2794)
			(stroke
				(width 0.1)
				(type default)
			)
			(layer "F.Fab")
		)
		(fp_line
			(start 0.12065 -0.3048)
			(end 0.67945 -0.3048)
			(stroke
				(width 0.1)
				(type default)
			)
			(layer "F.Fab")
		)
		(fp_line
			(start 0.12065 -0.2794)
			(end 0.12065 -0.3048)
			(stroke
				(width 0.1)
				(type default)
			)
			(layer "F.Fab")
		)
		(fp_line
			(start 0.67945 -0.3048)
			(end 0.67945 0.3048)
			(stroke
				(width 0.1)
				(type default)
			)
			(layer "F.Fab")
		)
		(fp_line
			(start 0.67945 0.3048)
			(end 0.120396 0.3048)
			(stroke
				(width 0.1)
				(type default)
			)
			(layer "F.Fab")
		)
		(pad "1" smd circle
			(at -0.40005 0)
			(size 0 0)
			(layers "F.Cu" "F.Mask" "F.Paste")
			(net "P3V3_OCP_V3_2")
		)
		(pad "2" smd circle
			(at 0.40005 0)
			(size 0 0)
			(layers "F.Cu" "F.Mask" "F.Paste")
			(net "SMB_OCP_V3_2_3V3AUX_BUF_SCL")
		)
	)
)
